# S9S_MB_2U (Grand Teton) — schematic parts with pin connectivity, parts 149–335 of 6093; source: Cadence DE-HDL packaged netlist (pstxprt.dat, pstxnet.dat, pstchip.dat)

C188  Q_CAP  0.1UF 25V 10% X7R  pkg 0402  page 155 : 1 = P3V3_AUX ; 2 = GND
C204  Q_CAP  0.1UF 25V 10% X7R  pkg 0402  page 206 : 1 = P3V3_DB2000_VDD ; 2 = GND
C205  Q_CAP  0.1UF 25V 10% X7R  pkg 0402  page 206 : 1 = P3V3_DB2000_VDD ; 2 = GND
C206  Q_CAP  0.1UF 25V 10% X7R  pkg 0402  page 206 : 1 = P3V3_DB2000_VDD ; 2 = GND
C207  Q_CAP  0.1UF 25V 10% X7R  pkg 0402  page 206 : 1 = P3V3_DB2000_VDD ; 2 = GND
C208  Q_CAP  10UF 6.3V 20% X6S  pkg C0603  page 206 : 1 = P3V3_DB2000_VDDR ; 2 = GND
C209  Q_CAP  10UF 6.3V 20% X6S  pkg C0603  page 206 : 1 = P3V3_DB2000_VDDA ; 2 = GND
C210  Q_CAP  0.1UF 25V 10% X7R  pkg 0402  page 206 : 1 = P3V3_DB2000_VDDR ; 2 = GND
C211  Q_CAP  0.1UF 25V 10% X7R  pkg 0402  page 206 : 1 = P3V3_DB2000_VDDA ; 2 = GND
C212  Q_CAP  47UF 4V 20% X6S  pkg C0805  page 74 : 1 = PVCCIN_CPU0 ; 2 = GND
C213  Q_CAP  47UF 4V 20% X6S  pkg C0805  page 74 : 1 = PVCCIN_CPU0 ; 2 = GND
C214  Q_CAP  47UF 4V 20% X6S  pkg C0805  page 74 : 1 = PVCCIN_CPU0 ; 2 = GND
C215  Q_CAP  47UF 4V 20% X6S  pkg C0805  page 74 : 1 = PVCCIN_CPU0 ; 2 = GND
C216  Q_CAP  47UF 4V 20% X6S  pkg C0805  page 74 : 1 = PVCCIN_CPU0 ; 2 = GND
C217  Q_CAP  47UF 4V 20% X6S  pkg C0805  page 74 : 1 = PVCCIN_CPU0 ; 2 = GND
C218  Q_CAP  47UF 4V 20% X6S  pkg C0805  page 74 : 1 = PVCCIN_CPU0 ; 2 = GND
C219  Q_CAP  47UF 4V 20% X6S  pkg C0805  page 74 : 1 = PVCCIN_CPU0 ; 2 = GND
C220  Q_CAP  47UF 4V 20% X6S  pkg C0805  page 74 : 1 = PVCCIN_CPU0 ; 2 = GND
C221  Q_CAP  10UF 6.3V 20% X6S  pkg C0402  page 77 : 1 = PVCCIN_CPU1 ; 2 = GND
C222  Q_CAP  10UF 6.3V 20% X6S  pkg C0402  page 77 : 1 = PVCCIN_CPU1 ; 2 = GND
C223  Q_CAP  10UF 6.3V 20% X6S  pkg C0402  page 77 : 1 = PVCCIN_CPU1 ; 2 = GND
C224  Q_CAP  10UF 6.3V 20% X6S  pkg C0402  page 77 : 1 = PVCCIN_CPU1 ; 2 = GND
C225  Q_CAP  47UF 4V 20% X6S  pkg C0805  page 77 : 1 = PVCCIN_CPU1 ; 2 = GND
C226  Q_CAP  10UF 6.3V 20% X6S  pkg C0402  page 77 : 1 = PVCCIN_CPU1 ; 2 = GND
C227  Q_CAP  10UF 6.3V 20% X6S  pkg C0402  page 77 : 1 = PVCCIN_CPU1 ; 2 = GND
C228  Q_CAP  10UF 6.3V 20% X6S  pkg C0402  page 77 : 1 = PVCCIN_CPU1 ; 2 = GND
C229  Q_CAP  10UF 6.3V 20% X6S  pkg C0402  page 77 : 1 = PVCCIN_CPU1 ; 2 = GND
C230  Q_CAP  47UF 4V 20% X6S  pkg C0805  page 77 : 1 = PVCCIN_CPU1 ; 2 = GND
C231  Q_CAP  10UF 6.3V 20% X6S  pkg C0402  page 77 : 1 = PVCCIN_CPU1 ; 2 = GND
C232  Q_CAP  10UF 6.3V 20% X6S  pkg C0402  page 77 : 1 = PVCCIN_CPU1 ; 2 = GND
C233  Q_CAP  10UF 6.3V 20% X6S  pkg C0402  page 77 : 1 = PVCCIN_CPU1 ; 2 = GND
C234  Q_CAP  10UF 6.3V 20% X6S  pkg C0402  page 77 : 1 = PVCCIN_CPU1 ; 2 = GND
C235  Q_CAP  47UF 4V 20% X6S  pkg C0805  page 77 : 1 = PVCCIN_CPU1 ; 2 = GND
C236  Q_CAP  10UF 6.3V 20% X6S  pkg C0402  page 77 : 1 = PVCCIN_CPU1 ; 2 = GND
C237  Q_CAP  10UF 6.3V 20% X6S  pkg C0402  page 77 : 1 = PVCCIN_CPU1 ; 2 = GND
C238  Q_CAP  10UF 6.3V 20% X6S  pkg C0402  page 77 : 1 = PVCCIN_CPU1 ; 2 = GND
C239  Q_CAP  10UF 6.3V 20% X6S  pkg C0402  page 77 : 1 = PVCCIN_CPU1 ; 2 = GND
C240  Q_CAP  47UF 4V 20% X6S  pkg C0805  page 77 : 1 = PVCCIN_CPU1 ; 2 = GND
C241  Q_CAP  10UF 6.3V 20% X6S  pkg C0402  page 77 : 1 = PVCCIN_CPU1 ; 2 = GND
C242  Q_CAP  10UF 6.3V 20% X6S  pkg C0402  page 77 : 1 = PVCCIN_CPU1 ; 2 = GND
C243  Q_CAP  10UF 6.3V 20% X6S  pkg C0402  page 77 : 1 = PVCCIN_CPU1 ; 2 = GND
C244  Q_CAP  10UF 6.3V 20% X6S  pkg C0402  page 77 : 1 = PVCCIN_CPU1 ; 2 = GND
C245  Q_CAP  47UF 4V 20% X6S  pkg C0805  page 77 : 1 = PVCCIN_CPU1 ; 2 = GND
C246  Q_CAP  10UF 6.3V 20% X6S  pkg C0402  page 77 : 1 = PVCCIN_CPU1 ; 2 = GND
C247  Q_CAP  10UF 6.3V 20% X6S  pkg C0402  page 77 : 1 = PVCCIN_CPU1 ; 2 = GND
C248  Q_CAP  10UF 6.3V 20% X6S  pkg C0402  page 77 : 1 = PVCCIN_CPU1 ; 2 = GND
C249  Q_CAP  10UF 6.3V 20% X6S  pkg C0402  page 77 : 1 = PVCCIN_CPU1 ; 2 = GND
C250  Q_CAP  47UF 4V 20% X6S  pkg C0805  page 77 : 1 = PVCCIN_CPU1 ; 2 = GND
C251  Q_CAP  10UF 6.3V 20% X6S  pkg C0402  page 77 : 1 = PVCCIN_CPU1 ; 2 = GND
C252  Q_CAP  10UF 6.3V 20% X6S  pkg C0402  page 77 : 1 = PVCCIN_CPU1 ; 2 = GND
C253  Q_CAP  10UF 6.3V 20% X6S  pkg C0402  page 77 : 1 = PVCCIN_CPU1 ; 2 = GND
C254  Q_CAP  10UF 6.3V 20% X6S  pkg C0402  page 77 : 1 = PVCCIN_CPU1 ; 2 = GND
C255  Q_CAP  47UF 4V 20% X6S  pkg C0805  page 77 : 1 = PVCCIN_CPU1 ; 2 = GND
C256  Q_CAP  10UF 6.3V 20% X6S  pkg C0402  page 77 : 1 = PVCCIN_CPU1 ; 2 = GND
C257  Q_CAP  10UF 6.3V 20% X6S  pkg C0402  page 77 : 1 = PVCCIN_CPU1 ; 2 = GND
C258  Q_CAP  10UF 6.3V 20% X6S  pkg C0402  page 77 : 1 = PVCCIN_CPU1 ; 2 = GND
C259  Q_CAP  10UF 6.3V 20% X6S  pkg C0402  page 77 : 1 = PVCCIN_CPU1 ; 2 = GND
C260  Q_CAP  47UF 4V 20% X6S  pkg C0805  page 77 : 1 = PVCCIN_CPU1 ; 2 = GND
C261  Q_CAP  10UF 6.3V 20% X6S  pkg C0402  page 77 : 1 = PVCCIN_CPU1 ; 2 = GND
C262  Q_CAP  10UF 6.3V 20% X6S  pkg C0402  page 77 : 1 = PVCCIN_CPU1 ; 2 = GND
C263  Q_CAP  10UF 6.3V 20% X6S  pkg C0402  page 77 : 1 = PVCCIN_CPU1 ; 2 = GND
C264  Q_CAP  10UF 6.3V 20% X6S  pkg C0402  page 77 : 1 = PVCCIN_CPU1 ; 2 = GND
C265  Q_CAP  47UF 4V 20% X6S  pkg C0805  page 77 : 1 = PVCCIN_CPU1 ; 2 = GND
C266  Q_CAP  10UF 6.3V 20% X6S  pkg C0402  page 77 : 1 = PVCCIN_CPU1 ; 2 = GND
C267  Q_CAP  10UF 6.3V 20% X6S  pkg C0402  page 77 : 1 = PVCCIN_CPU1 ; 2 = GND
C268  Q_CAP  10UF 6.3V 20% X6S  pkg C0402  page 77 : 1 = PVCCIN_CPU1 ; 2 = GND
C269  Q_CAP  10UF 6.3V 20% X6S  pkg C0402  page 77 : 1 = PVCCIN_CPU1 ; 2 = GND
C270  Q_CAP  47UF 4V 20% X6S  pkg C0805  page 77 : 1 = PVCCIN_CPU1 ; 2 = GND
C271  Q_CAP  22UF 4V 20% X6S  pkg C0402  page 77 : 1 = PVCCIN_CPU1 ; 2 = GND
C272  Q_CAP  22UF 4V 20% X6S  pkg C0402  page 77 : 1 = PVCCIN_CPU1 ; 2 = GND
C273  Q_CAP  22UF 4V 20% X6S  pkg C0402  page 77 : 1 = PVCCIN_CPU1 ; 2 = GND
C274  Q_CAP  22UF 4V 20% X6S  pkg C0402  page 77 : 1 = PVCCIN_CPU1 ; 2 = GND
C275  Q_CAP  22UF 4V 20% X6S  pkg C0402  page 77 : 1 = PVCCIN_CPU1 ; 2 = GND
C276  Q_CAP  22UF 4V 20% X6S  pkg C0402  page 77 : 1 = PVCCIN_CPU1 ; 2 = GND
C277  Q_CAP  22UF 4V 20% X6S  pkg C0402  page 77 : 1 = PVCCIN_CPU1 ; 2 = GND
C278  Q_CAP  22UF 4V 20% X6S  pkg C0402  page 77 : 1 = PVCCIN_CPU1 ; 2 = GND
C279  Q_CAP  22UF 4V 20% X6S  pkg C0402  page 77 : 1 = PVCCIN_CPU1 ; 2 = GND
C280  Q_CAP  22UF 4V 20% X6S  pkg C0402  page 77 : 1 = PVCCIN_CPU1 ; 2 = GND
C281  Q_CAP  22UF 4V 20% X6S  pkg C0402  page 77 : 1 = PVCCIN_CPU1 ; 2 = GND
C282  Q_CAP  22UF 4V 20% X6S  pkg C0402  page 77 : 1 = PVCCIN_CPU1 ; 2 = GND
C283  Q_CAP  22UF 4V 20% X6S  pkg C0402  page 77 : 1 = PVCCIN_CPU1 ; 2 = GND
C284  Q_CAP  22UF 4V 20% X6S  pkg C0402  page 77 : 1 = PVCCIN_CPU1 ; 2 = GND
C285  Q_CAP  22UF 4V 20% X6S  pkg C0402  page 77 : 1 = PVCCIN_CPU1 ; 2 = GND
C286  Q_CAP  22UF 4V 20% X6S  pkg C0402  page 77 : 1 = PVCCIN_CPU1 ; 2 = GND
C287  Q_CAP  22UF 4V 20% X6S  pkg C0402  page 77 : 1 = PVCCIN_CPU1 ; 2 = GND
C288  Q_CAP  22UF 4V 20% X6S  pkg C0402  page 77 : 1 = PVCCIN_CPU1 ; 2 = GND
C289  Q_CAP  22UF 4V 20% X6S  pkg C0402  page 77 : 1 = PVCCIN_CPU1 ; 2 = GND
C290  Q_CAP  22UF 4V 20% X6S  pkg C0402  page 77 : 1 = PVCCIN_CPU1 ; 2 = GND
C291  Q_CAP  22UF 4V 20% X6S  pkg C0402  page 77 : 1 = PVCCIN_CPU1 ; 2 = GND
C292  Q_CAP  22UF 4V 20% X6S  pkg C0402  page 77 : 1 = PVCCIN_CPU1 ; 2 = GND
C293  Q_CAP  22UF 4V 20% X6S  pkg C0402  page 77 : 1 = PVCCIN_CPU1 ; 2 = GND
C294  Q_CAP  22UF 4V 20% X6S  pkg C0402  page 77 : 1 = PVCCIN_CPU1 ; 2 = GND
C295  Q_CAP  22UF 4V 20% X6S  pkg C0402  page 77 : 1 = PVCCIN_CPU1 ; 2 = GND
C296  Q_CAP  22UF 4V 20% X6S  pkg C0402  page 77 : 1 = PVCCIN_CPU1 ; 2 = GND
C297  Q_CAP  22UF 4V 20% X6S  pkg C0402  page 77 : 1 = PVCCIN_CPU1 ; 2 = GND
C298  Q_CAP  22UF 4V 20% X6S  pkg C0402  page 77 : 1 = PVCCIN_CPU1 ; 2 = GND
C299  Q_CAP  22UF 4V 20% X6S  pkg C0402  page 77 : 1 = PVCCIN_CPU1 ; 2 = GND
C300  Q_CAP  22UF 4V 20% X6S  pkg C0402  page 77 : 1 = PVCCIN_CPU1 ; 2 = GND
C301  Q_CAP  22UF 4V 20% X6S  pkg C0402  page 77 : 1 = PVCCIN_CPU1 ; 2 = GND
C302  Q_CAP  22UF 4V 20% X6S  pkg C0402  page 77 : 1 = PVCCIN_CPU1 ; 2 = GND
C303  Q_CAP  22UF 4V 20% X6S  pkg C0402  page 77 : 1 = PVCCIN_CPU1 ; 2 = GND
C304  Q_CAP  22UF 4V 20% X6S  pkg C0402  page 77 : 1 = PVCCIN_CPU1 ; 2 = GND
C305  Q_CAP  22UF 4V 20% X6S  pkg C0402  page 77 : 1 = PVCCIN_CPU1 ; 2 = GND
C306  Q_CAP  22UF 4V 20% X6S  pkg C0402  page 77 : 1 = PVCCIN_CPU1 ; 2 = GND
C307  Q_CAP  22UF 4V 20% X6S  pkg C0402  page 77 : 1 = PVCCIN_CPU1 ; 2 = GND
C308  Q_CAP  22UF 4V 20% X6S  pkg C0402  page 77 : 1 = PVCCIN_CPU1 ; 2 = GND
C309  Q_CAP  22UF 4V 20% X6S  pkg C0402  page 77 : 1 = PVCCIN_CPU1 ; 2 = GND
C310  Q_CAP  22UF 4V 20% X6S  pkg C0402  page 77 : 1 = PVNN_MAIN_CPU1 ; 2 = GND
C311  Q_CAP  47UF 4V 20% X6S  pkg C0805  page 78 : 1 = PVCCIN_CPU1 ; 2 = GND
C312  Q_CAP  47UF 4V 20% X6S  pkg C0805  page 78 : 1 = PVCCIN_CPU1 ; 2 = GND
C313  Q_CAP  47UF 4V 20% X6S  pkg C0805  page 78 : 1 = PVCCIN_CPU1 ; 2 = GND
C314  Q_CAP  47UF 4V 20% X6S  pkg C0805  page 78 : 1 = PVCCIN_CPU1 ; 2 = GND
C315  Q_CAP  47UF 4V 20% X6S  pkg C0805  page 78 : 1 = PVCCIN_CPU1 ; 2 = GND
C316  Q_CAP  47UF 4V 20% X6S  pkg C0805  page 78 : 1 = PVCCIN_CPU1 ; 2 = GND
C317  Q_CAP  47UF 4V 20% X6S  pkg C0805  page 78 : 1 = PVCCIN_CPU1 ; 2 = GND
C318  Q_CAP  47UF 4V 20% X6S  pkg C0805  page 78 : 1 = PVCCIN_CPU1 ; 2 = GND
C320  Q_CAP  47UF 4V 20% X6S  pkg C0805  page 78 : 1 = PVCCIN_CPU1 ; 2 = GND
C321  Q_CAP  47UF 4V 20% X6S  pkg C0805  page 78 : 1 = PVCCIN_CPU1 ; 2 = GND
C322  Q_CAP  47UF 4V 20% X6S  pkg C0805  page 79 : 1 = PVCCIN_CPU1 ; 2 = GND
C323  Q_CAP  47UF 4V 20% X6S  pkg C0805  page 78 : 1 = PVCCIN_CPU1 ; 2 = GND
C324  Q_CAP  47UF 4V 20% X6S  pkg C0805  page 78 : 1 = PVCCIN_CPU1 ; 2 = GND
C325  Q_CAP  47UF 4V 20% X6S  pkg C0805  page 79 : 1 = PVCCIN_CPU1 ; 2 = GND
C326  Q_CAP  47UF 4V 20% X6S  pkg C0805  page 78 : 1 = PVCCIN_CPU1 ; 2 = GND
C327  Q_CAP  47UF 4V 20% X6S  pkg C0805  page 78 : 1 = PVCCIN_CPU1 ; 2 = GND
C328  Q_CAP  47UF 4V 20% X6S  pkg C0805  page 79 : 1 = PVCCIN_CPU1 ; 2 = GND
C329  Q_CAP  47UF 4V 20% X6S  pkg C0805  page 78 : 1 = PVCCIN_CPU1 ; 2 = GND
C330  Q_CAP  47UF 4V 20% X6S  pkg C0805  page 78 : 1 = PVCCIN_CPU1 ; 2 = GND
C332  Q_CAP  47UF 4V 20% X6S  pkg C0805  page 78 : 1 = PVCCIN_CPU1 ; 2 = GND
C333  Q_CAP  47UF 4V 20% X6S  pkg C0805  page 78 : 1 = PVCCIN_CPU1 ; 2 = GND
C335  Q_CAP  47UF 4V 20% X6S  pkg C0805  page 78 : 1 = PVCCIN_CPU1 ; 2 = GND
C336  Q_CAP  47UF 4V 20% X6S  pkg C0805  page 78 : 1 = PVCCIN_CPU1 ; 2 = GND
C337  Q_CAP  47UF 4V 20% X6S  pkg C0805  page 78 : 1 = PVCCIN_CPU1 ; 2 = GND
C338  Q_CAP  47UF 4V 20% X6S  pkg C0805  page 78 : 1 = PVCCIN_CPU1 ; 2 = GND
C339  Q_CAP  47UF 4V 20% X6S  pkg C0805  page 78 : 1 = PVCCIN_CPU1 ; 2 = GND
C341  Q_CAP  47UF 4V 20% X6S  pkg C0805  page 79 : 1 = PVCCIN_CPU1 ; 2 = GND
C342  Q_CAP  47UF 4V 20% X6S  pkg C0805  page 79 : 1 = PVCCIN_CPU1 ; 2 = GND
C343  Q_CAP  47UF 4V 20% X6S  pkg C0805  page 79 : 1 = PVCCIN_CPU1 ; 2 = GND
C344  Q_CAP  47UF 4V 20% X6S  pkg C0805  page 79 : 1 = PVCCIN_CPU1 ; 2 = GND
C345  Q_CAP  47UF 4V 20% X6S  pkg C0805  page 79 : 1 = PVCCIN_CPU1 ; 2 = GND
C346  Q_CAP  47UF 4V 20% X6S  pkg C0805  page 79 : 1 = PVCCIN_CPU1 ; 2 = GND
C347  Q_CAP  47UF 4V 20% X6S  pkg C0805  page 79 : 1 = PVCCIN_CPU1 ; 2 = GND
C348  Q_CAP  47UF 4V 20% X6S  pkg C0805  page 79 : 1 = PVCCIN_CPU1 ; 2 = GND
C349  Q_CAP  47UF 4V 20% X6S  pkg C0805  page 78 : 1 = PVCCIN_CPU1 ; 2 = GND
C350  Q_CAP  47UF 4V 20% X6S  pkg C0805  page 79 : 1 = PVCCIN_CPU1 ; 2 = GND
C351  Q_CAP  47UF 4V 20% X6S  pkg C0805  page 78 : 1 = PVCCIN_CPU1 ; 2 = GND
C352  Q_CAP  47UF 4V 20% X6S  pkg C0805  page 79 : 1 = PVCCIN_CPU1 ; 2 = GND
C353  Q_CAP  47UF 4V 20% X6S  pkg C0805  page 78 : 1 = PVCCIN_CPU1 ; 2 = GND
C354  Q_CAP  47UF 4V 20% X6S  pkg C0805  page 79 : 1 = PVCCIN_CPU1 ; 2 = GND
C355  Q_CAP  47UF 4V 20% X6S  pkg C0805  page 75 : 1 = PVCCIN_CPU0 ; 2 = GND
C356  Q_CAP  47UF 4V 20% X6S  pkg C0805  page 75 : 1 = PVCCIN_CPU0 ; 2 = GND
C357  Q_CAP  47UF 4V 20% X6S  pkg C0805  page 75 : 1 = PVCCIN_CPU0 ; 2 = GND
C358  Q_CAP  47UF 4V 20% X6S  pkg C0805  page 75 : 1 = PVCCIN_CPU0 ; 2 = GND
C359  Q_CAP  47UF 4V 20% X6S  pkg C0805  page 75 : 1 = PVCCIN_CPU0 ; 2 = GND
C360  Q_CAP  47UF 4V 20% X6S  pkg C0805  page 75 : 1 = PVCCIN_CPU0 ; 2 = GND
C361  Q_CAP  47UF 4V 20% X6S  pkg C0805  page 75 : 1 = PVCCIN_CPU0 ; 2 = GND
C362  Q_CAP  47UF 4V 20% X6S  pkg C0805  page 75 : 1 = PVCCIN_CPU0 ; 2 = GND
C363  Q_CAP  47UF 4V 20% X6S  pkg C0805  page 75 : 1 = PVCCIN_CPU0 ; 2 = GND
C364  Q_CAP  47UF 4V 20% X6S  pkg C0805  page 75 : 1 = PVCCIN_CPU0 ; 2 = GND
C365  Q_CAP  47UF 4V 20% X6S  pkg C0805  page 75 : 1 = PVCCIN_CPU0 ; 2 = GND
C366  Q_CAP  47UF 4V 20% X6S  pkg C0805  page 76 : 1 = PVCCIN_CPU0 ; 2 = GND
C367  Q_CAP  47UF 4V 20% X6S  pkg C0805  page 75 : 1 = PVCCIN_CPU0 ; 2 = GND
C368  Q_CAP  47UF 4V 20% X6S  pkg C0805  page 75 : 1 = PVCCIN_CPU0 ; 2 = GND
C369  Q_CAP  47UF 4V 20% X6S  pkg C0805  page 76 : 1 = PVCCIN_CPU0 ; 2 = GND
C370  Q_CAP  47UF 4V 20% X6S  pkg C0805  page 75 : 1 = PVCCIN_CPU0 ; 2 = GND
C371  Q_CAP  47UF 4V 20% X6S  pkg C0805  page 75 : 1 = PVCCIN_CPU0 ; 2 = GND
C372  Q_CAP  47UF 4V 20% X6S  pkg C0805  page 76 : 1 = PVCCIN_CPU0 ; 2 = GND
C373  Q_CAP  47UF 4V 20% X6S  pkg C0805  page 75 : 1 = PVCCIN_CPU0 ; 2 = GND
C374  Q_CAP  47UF 4V 20% X6S  pkg C0805  page 76 : 1 = PVCCIN_CPU0 ; 2 = GND
C376  Q_CAP  47UF 4V 20% X6S  pkg C0805  page 75 : 1 = PVCCIN_CPU0 ; 2 = GND
C377  Q_CAP  47UF 4V 20% X6S  pkg C0805  page 76 : 1 = PVCCIN_CPU0 ; 2 = GND
C379  Q_CAP  47UF 4V 20% X6S  pkg C0805  page 75 : 1 = PVCCIN_CPU0 ; 2 = GND
C380  Q_CAP  47UF 4V 20% X6S  pkg C0805  page 76 : 1 = PVCCIN_CPU0 ; 2 = GND
C381  Q_CAP  47UF 4V 20% X6S  pkg C0805  page 75 : 1 = PVCCIN_CPU0 ; 2 = GND
C382  Q_CAP  47UF 4V 20% X6S  pkg C0805  page 75 : 1 = PVCCIN_CPU0 ; 2 = GND
C383  Q_CAP  47UF 4V 20% X6S  pkg C0805  page 76 : 1 = PVCCIN_CPU0 ; 2 = GND
C385  Q_CAP  47UF 4V 20% X6S  pkg C0805  page 75 : 1 = PVCCIN_CPU0 ; 2 = GND
C386  Q_CAP  47UF 4V 20% X6S  pkg C0805  page 76 : 1 = PVCCIN_CPU0 ; 2 = GND
C387  Q_CAP  47UF 4V 20% X6S  pkg C0805  page 75 : 1 = PVCCIN_CPU0 ; 2 = GND
C388  Q_CAP  47UF 4V 20% X6S  pkg C0805  page 76 : 1 = PVCCIN_CPU0 ; 2 = GND
C389  Q_CAP  47UF 4V 20% X6S  pkg C0805  page 75 : 1 = PVCCIN_CPU0 ; 2 = GND
C390  Q_CAP  47UF 4V 20% X6S  pkg C0805  page 76 : 1 = PVCCIN_CPU0 ; 2 = GND
C391  Q_CAP  47UF 4V 20% X6S  pkg C0805  page 75 : 1 = PVCCIN_CPU0 ; 2 = GND
C392  Q_CAP  47UF 4V 20% X6S  pkg C0805  page 76 : 1 = PVCCIN_CPU0 ; 2 = GND
C393  Q_CAP  47UF 4V 20% X6S  pkg C0805  page 75 : 1 = PVCCIN_CPU0 ; 2 = GND
C394  Q_CAP  47UF 4V 20% X6S  pkg C0805  page 76 : 1 = PVCCIN_CPU0 ; 2 = GND
C395  Q_CAP  47UF 4V 20% X6S  pkg C0805  page 75 : 1 = PVNN_MAIN_CPU0 ; 2 = GND
C396  Q_CAP  47UF 4V 20% X6S  pkg C0805  page 76 : 1 = PVCCIN_CPU0 ; 2 = GND
